(kicad_pcb
	(version 20260206)
	(generator "pcbnew")
	(generator_version "10.0")
	(general
		(thickness 1.6)
		(legacy_teardrops no)
	)
	(paper "A4")
	(title_block
		(title "04192023_DAF0TMB3IC0_F0TG_MB_C_brd_V02_OCP.brd")
		(comment 1 "Grand Teton / footprints 1402-1408 of 8354")
	)
	(layers
		(0 "F.Cu" signal "TOP")
		(4 "In1.Cu" signal "GND")
		(6 "In2.Cu" signal "IN1")
		(8 "In3.Cu" signal "GND1")
		(10 "In4.Cu" signal "IN2")
		(12 "In5.Cu" signal "GND2")
		(14 "In6.Cu" signal "IN3")
		(16 "In7.Cu" signal "GND3")
		(18 "In8.Cu" signal "VCC")
		(20 "In9.Cu" signal "VCC1")
		(22 "In10.Cu" signal "GND4")
		(24 "In11.Cu" signal "IN4")
		(26 "In12.Cu" signal "GND5")
		(28 "In13.Cu" signal "IN5")
		(30 "In14.Cu" signal "GND6")
		(32 "In15.Cu" signal "IN6")
		(34 "In16.Cu" signal "GND7")
		(2 "B.Cu" signal "BOTTOM")
		(9 "F.Adhes" user "F.Adhesive")
		(11 "B.Adhes" user "B.Adhesive")
		(13 "F.Paste" user "Package Geometry/Pastemask Top")
		(15 "B.Paste" user "Package Geometry/Pastemask Bottom")
		(5 "F.SilkS" user "Ref Des/Silkscreen Top")
		(7 "B.SilkS" user "Ref Des/Silkscreen Bottom")
		(1 "F.Mask" user "Board Geometry/Soldermask Top")
		(3 "B.Mask" user "Board Geometry/Soldermask Bottom")
		(17 "Dwgs.User" user "User.Drawings")
		(19 "Cmts.User" user "User.Comments")
		(21 "Eco1.User" user "User.Eco1")
		(23 "Eco2.User" user "User.Eco2")
		(25 "Edge.Cuts" user "Board Geometry/Outline")
		(27 "Margin" user)
		(31 "F.CrtYd" user "Package Geometry/Place Bound Top")
		(29 "B.CrtYd" user "Package Geometry/Place Bound Bottom")
		(35 "F.Fab" user "Ref Des/Assembly Top")
		(33 "B.Fab" user "Ref Des/Assembly Bottom")
	)
	(footprint ""
		(layer "F.Cu")
		(at 329.360022 -31.937706)
		(property "Reference" "C2043"
			(at 0 0 0)
			(layer "F.SilkS")
			(hide yes)
			(effects
				(font
					(size 1.27 1.27)
				)
			)
		)
		(property "Value" ""
			(at 0 0 0)
			(layer "F.Fab")
			(effects
				(font
					(size 1.27 1.27)
				)
			)
		)
		(duplicate_pad_numbers_are_jumpers no)
		(fp_line
			(start -0.7874 -0.4064)
			(end 0.7874 -0.4064)
			(stroke
				(width 0.1524)
				(type default)
			)
			(layer "F.SilkS")
		)
		(fp_line
			(start -0.7874 0.4064)
			(end -0.7874 -0.4064)
			(stroke
				(width 0.1524)
				(type default)
			)
			(layer "F.SilkS")
		)
		(fp_line
			(start 0.7874 -0.4064)
			(end 0.7874 0.4064)
			(stroke
				(width 0.1524)
				(type default)
			)
			(layer "F.SilkS")
		)
		(fp_line
			(start 0.7874 0.4064)
			(end -0.7874 0.4064)
			(stroke
				(width 0.1524)
				(type default)
			)
			(layer "F.SilkS")
		)
		(fp_line
			(start -0.67945 -0.305054)
			(end -0.12065 -0.305054)
			(stroke
				(width 0.1)
				(type default)
			)
			(layer "F.Fab")
		)
		(fp_line
			(start -0.67945 0.3048)
			(end -0.67945 -0.305054)
			(stroke
				(width 0.1)
				(type default)
			)
			(layer "F.Fab")
		)
		(fp_line
			(start -0.12065 -0.305054)
			(end -0.12065 -0.2794)
			(stroke
				(width 0.1)
				(type default)
			)
			(layer "F.Fab")
		)
		(fp_line
			(start -0.12065 -0.2794)
			(end 0.12065 -0.2794)
			(stroke
				(width 0.1)
				(type default)
			)
			(layer "F.Fab")
		)
		(fp_line
			(start -0.12065 0.2794)
			(end -0.12065 0.3048)
			(stroke
				(width 0.1)
				(type default)
			)
			(layer "F.Fab")
		)
		(fp_line
			(start -0.12065 0.3048)
			(end -0.67945 0.3048)
			(stroke
				(width 0.1)
				(type default)
			)
			(layer "F.Fab")
		)
		(fp_line
			(start 0.120396 0.2794)
			(end -0.12065 0.2794)
			(stroke
				(width 0.1)
				(type default)
			)
			(layer "F.Fab")
		)
		(fp_line
			(start 0.120396 0.3048)
			(end 0.120396 0.2794)
			(stroke
				(width 0.1)
				(type default)
			)
			(layer "F.Fab")
		)
		(fp_line
			(start 0.12065 -0.3048)
			(end 0.67945 -0.3048)
			(stroke
				(width 0.1)
				(type default)
			)
			(layer "F.Fab")
		)
		(fp_line
			(start 0.12065 -0.2794)
			(end 0.12065 -0.3048)
			(stroke
				(width 0.1)
				(type default)
			)
			(layer "F.Fab")
		)
		(fp_line
			(start 0.67945 -0.3048)
			(end 0.67945 0.3048)
			(stroke
				(width 0.1)
				(type default)
			)
			(layer "F.Fab")
		)
		(fp_line
			(start 0.67945 0.3048)
			(end 0.120396 0.3048)
			(stroke
				(width 0.1)
				(type default)
			)
			(layer "F.Fab")
		)
		(pad "1" smd circle
			(at -0.40005 0)
			(size 0 0)
			(layers "F.Cu" "F.Mask" "F.Paste")
			(net "P3V3_ADC_MAM")
		)
		(pad "2" smd circle
			(at 0.40005 0)
			(size 0 0)
			(layers "F.Cu" "F.Mask" "F.Paste")
			(net "GND")
		)
	)
	(footprint ""
		(layer "F.Cu")
		(at 88.908128 -339.630258 -90)
		(property "Reference" "PC383"
			(at 0 0 270)
			(layer "F.SilkS")
			(hide yes)
			(effects
				(font
					(size 1.27 1.27)
				)
			)
		)
		(property "Value" ""
			(at 0 0 270)
			(layer "F.Fab")
			(effects
				(font
					(size 1.27 1.27)
				)
			)
		)
		(duplicate_pad_numbers_are_jumpers no)
		(fp_line
			(start -0.7874 0.4064)
			(end -0.7874 -0.4064)
			(stroke
				(width 0.1524)
				(type default)
			)
			(layer "F.SilkS")
		)
		(fp_line
			(start 0.7874 0.4064)
			(end -0.7874 0.4064)
			(stroke
				(width 0.1524)
				(type default)
			)
			(layer "F.SilkS")
		)
		(fp_line
			(start -0.7874 -0.4064)
			(end 0.7874 -0.4064)
			(stroke
				(width 0.1524)
				(type default)
			)
			(layer "F.SilkS")
		)
		(fp_line
			(start 0.7874 -0.4064)
			(end 0.7874 0.4064)
			(stroke
				(width 0.1524)
				(type default)
			)
			(layer "F.SilkS")
		)
		(fp_line
			(start -0.67945 0.3048)
			(end -0.67945 -0.305054)
			(stroke
				(width 0.1)
				(type default)
			)
			(layer "F.Fab")
		)
		(fp_line
			(start -0.12065 0.3048)
			(end -0.67945 0.3048)
			(stroke
				(width 0.1)
				(type default)
			)
			(layer "F.Fab")
		)
		(fp_line
			(start 0.120396 0.3048)
			(end 0.120396 0.2794)
			(stroke
				(width 0.1)
				(type default)
			)
			(layer "F.Fab")
		)
		(fp_line
			(start 0.67945 0.3048)
			(end 0.120396 0.3048)
			(stroke
				(width 0.1)
				(type default)
			)
			(layer "F.Fab")
		)
		(fp_line
			(start -0.12065 0.2794)
			(end -0.12065 0.3048)
			(stroke
				(width 0.1)
				(type default)
			)
			(layer "F.Fab")
		)
		(fp_line
			(start 0.120396 0.2794)
			(end -0.12065 0.2794)
			(stroke
				(width 0.1)
				(type default)
			)
			(layer "F.Fab")
		)
		(fp_line
			(start -0.12065 -0.2794)
			(end 0.12065 -0.2794)
			(stroke
				(width 0.1)
				(type default)
			)
			(layer "F.Fab")
		)
		(fp_line
			(start 0.12065 -0.2794)
			(end 0.12065 -0.3048)
			(stroke
				(width 0.1)
				(type default)
			)
			(layer "F.Fab")
		)
		(fp_line
			(start 0.12065 -0.3048)
			(end 0.67945 -0.3048)
			(stroke
				(width 0.1)
				(type default)
			)
			(layer "F.Fab")
		)
		(fp_line
			(start 0.67945 -0.3048)
			(end 0.67945 0.3048)
			(stroke
				(width 0.1)
				(type default)
			)
			(layer "F.Fab")
		)
		(fp_line
			(start -0.67945 -0.305054)
			(end -0.12065 -0.305054)
			(stroke
				(width 0.1)
				(type default)
			)
			(layer "F.Fab")
		)
		(fp_line
			(start -0.12065 -0.305054)
			(end -0.12065 -0.2794)
			(stroke
				(width 0.1)
				(type default)
			)
			(layer "F.Fab")
		)
		(pad "1" smd circle
			(at -0.40005 0 270)
			(size 0 0)
			(layers "F.Cu" "F.Mask" "F.Paste")
			(net "SW_PVDDCR_CPU1_P1_BOOT1_R")
		)
		(pad "2" smd circle
			(at 0.40005 0 270)
			(size 0 0)
			(layers "F.Cu" "F.Mask" "F.Paste")
			(net "SW_PVDDCR_CPU1_P1_BOOTR1")
		)
	)
	(footprint ""
		(layer "F.Cu")
		(at 457.314046 -32.053276)
		(property "Reference" "H29"
			(at -5.8166 -5.552948 0)
			(unlocked yes)
			(layer "F.SilkS")
			(effects
				(font
					(size 0.7874 0.5842)
					(thickness 0.1524)
				)
				(justify left)
			)
		)
		(property "Value" ""
			(at 0 0 0)
			(layer "F.Fab")
			(effects
				(font
					(size 1.27 1.27)
				)
			)
		)
		(duplicate_pad_numbers_are_jumpers no)
		(fp_circle
			(center 0 0)
			(end 2.4003 0)
			(stroke
				(width 0.1524)
				(type default)
			)
			(fill no)
			(layer "F.SilkS")
		)
		(fp_circle
			(center 0 0)
			(end 6.5913 0)
			(stroke
				(width 0.1524)
				(type default)
			)
			(fill no)
			(layer "B.SilkS")
		)
		(fp_circle
			(center 0 0)
			(end 6.5913 0)
			(stroke
				(width 0.1)
				(type default)
			)
			(fill no)
			(layer "B.Fab")
		)
		(fp_circle
			(center 0 0)
			(end 2.4003 0)
			(stroke
				(width 0.1)
				(type default)
			)
			(fill no)
			(layer "F.Fab")
		)
		(pad "" np_thru_hole circle
			(at 0 0)
			(size 3.175 3.175)
			(drill 3.175)
			(layers "*.Cu" "*.Mask")
			(clearance 0.381)
			(thermal_gap 0.381)
		)
		(zone
			(layers "F.Cu" "B.Cu" "In1.Cu" "In2.Cu" "In3.Cu" "In4.Cu" "In5.Cu" "In6.Cu"
				"In7.Cu" "In8.Cu" "In9.Cu" "In10.Cu" "In11.Cu" "In12.Cu" "In13.Cu" "In14.Cu"
				"In15.Cu" "In16.Cu"
			)
			(hatch none 0.5)
			(connect_pads
				(clearance 0)
			)
			(min_thickness 0.25)
			(keepout
				(tracks not_allowed)
				(vias allowed)
				(pads allowed)
				(copperpour not_allowed)
				(footprints allowed)
			)
			(placement
				(enabled no)
				(sheetname "")
			)
			(fill
				(thermal_gap 0.5)
				(thermal_bridge_width 0.5)
				(island_removal_mode 0)
			)
			(polygon
				(pts
					(arc
						(start 459.409546 -32.053276)
						(mid 455.218546 -32.053276)
						(end 459.409546 -32.053276)
					)
				)
			)
		)
	)
	(footprint ""
		(layer "F.Cu")
		(at 29.464 -434.9623)
		(property "Reference" "R4603"
			(at 0 0 0)
			(layer "F.SilkS")
			(hide yes)
			(effects
				(font
					(size 1.27 1.27)
				)
			)
		)
		(property "Value" ""
			(at 0 0 0)
			(layer "F.Fab")
			(effects
				(font
					(size 1.27 1.27)
				)
			)
		)
		(duplicate_pad_numbers_are_jumpers no)
		(fp_line
			(start -0.7874 -0.4064)
			(end 0.7874 -0.4064)
			(stroke
				(width 0.1524)
				(type default)
			)
			(layer "F.SilkS")
		)
		(fp_line
			(start -0.7874 0.4064)
			(end -0.7874 -0.4064)
			(stroke
				(width 0.1524)
				(type default)
			)
			(layer "F.SilkS")
		)
		(fp_line
			(start 0.7874 -0.4064)
			(end 0.7874 0.4064)
			(stroke
				(width 0.1524)
				(type default)
			)
			(layer "F.SilkS")
		)
		(fp_line
			(start 0.7874 0.4064)
			(end -0.7874 0.4064)
			(stroke
				(width 0.1524)
				(type default)
			)
			(layer "F.SilkS")
		)
		(fp_line
			(start -0.67945 -0.305054)
			(end -0.12065 -0.305054)
			(stroke
				(width 0.1)
				(type default)
			)
			(layer "F.Fab")
		)
		(fp_line
			(start -0.67945 0.3048)
			(end -0.67945 -0.305054)
			(stroke
				(width 0.1)
				(type default)
			)
			(layer "F.Fab")
		)
		(fp_line
			(start -0.12065 -0.305054)
			(end -0.12065 -0.2794)
			(stroke
				(width 0.1)
				(type default)
			)
			(layer "F.Fab")
		)
		(fp_line
			(start -0.12065 -0.2794)
			(end 0.12065 -0.2794)
			(stroke
				(width 0.1)
				(type default)
			)
			(layer "F.Fab")
		)
		(fp_line
			(start -0.12065 0.2794)
			(end -0.12065 0.3048)
			(stroke
				(width 0.1)
				(type default)
			)
			(layer "F.Fab")
		)
		(fp_line
			(start -0.12065 0.3048)
			(end -0.67945 0.3048)
			(stroke
				(width 0.1)
				(type default)
			)
			(layer "F.Fab")
		)
		(fp_line
			(start 0.120396 0.2794)
			(end -0.12065 0.2794)
			(stroke
				(width 0.1)
				(type default)
			)
			(layer "F.Fab")
		)
		(fp_line
			(start 0.120396 0.3048)
			(end 0.120396 0.2794)
			(stroke
				(width 0.1)
				(type default)
			)
			(layer "F.Fab")
		)
		(fp_line
			(start 0.12065 -0.3048)
			(end 0.67945 -0.3048)
			(stroke
				(width 0.1)
				(type default)
			)
			(layer "F.Fab")
		)
		(fp_line
			(start 0.12065 -0.2794)
			(end 0.12065 -0.3048)
			(stroke
				(width 0.1)
				(type default)
			)
			(layer "F.Fab")
		)
		(fp_line
			(start 0.67945 -0.3048)
			(end 0.67945 0.3048)
			(stroke
				(width 0.1)
				(type default)
			)
			(layer "F.Fab")
		)
		(fp_line
			(start 0.67945 0.3048)
			(end 0.120396 0.3048)
			(stroke
				(width 0.1)
				(type default)
			)
			(layer "F.Fab")
		)
		(pad "1" smd circle
			(at -0.40005 0)
			(size 0 0)
			(layers "F.Cu" "F.Mask" "F.Paste")
			(net "SMB_BMC_GPU_EN")
		)
		(pad "2" smd circle
			(at 0.40005 0)
			(size 0 0)
			(layers "F.Cu" "F.Mask" "F.Paste")
			(net "GND")
		)
	)
	(footprint ""
		(layer "F.Cu")
		(at 117.347238 -41.17975 -90)
		(property "Reference" "R6282"
			(at 0 0 270)
			(layer "F.SilkS")
			(hide yes)
			(effects
				(font
					(size 1.27 1.27)
				)
			)
		)
		(property "Value" ""
			(at 0 0 270)
			(layer "F.Fab")
			(effects
				(font
					(size 1.27 1.27)
				)
			)
		)
		(duplicate_pad_numbers_are_jumpers no)
		(fp_line
			(start -0.7874 0.4064)
			(end -0.7874 -0.4064)
			(stroke
				(width 0.1524)
				(type default)
			)
			(layer "F.SilkS")
		)
		(fp_line
			(start 0.7874 0.4064)
			(end -0.7874 0.4064)
			(stroke
				(width 0.1524)
				(type default)
			)
			(layer "F.SilkS")
		)
		(fp_line
			(start -0.7874 -0.4064)
			(end 0.7874 -0.4064)
			(stroke
				(width 0.1524)
				(type default)
			)
			(layer "F.SilkS")
		)
		(fp_line
			(start 0.7874 -0.4064)
			(end 0.7874 0.4064)
			(stroke
				(width 0.1524)
				(type default)
			)
			(layer "F.SilkS")
		)
		(fp_line
			(start -0.67945 0.3048)
			(end -0.67945 -0.305054)
			(stroke
				(width 0.1)
				(type default)
			)
			(layer "F.Fab")
		)
		(fp_line
			(start -0.12065 0.3048)
			(end -0.67945 0.3048)
			(stroke
				(width 0.1)
				(type default)
			)
			(layer "F.Fab")
		)
		(fp_line
			(start 0.120396 0.3048)
			(end 0.120396 0.2794)
			(stroke
				(width 0.1)
				(type default)
			)
			(layer "F.Fab")
		)
		(fp_line
			(start 0.67945 0.3048)
			(end 0.120396 0.3048)
			(stroke
				(width 0.1)
				(type default)
			)
			(layer "F.Fab")
		)
		(fp_line
			(start -0.12065 0.2794)
			(end -0.12065 0.3048)
			(stroke
				(width 0.1)
				(type default)
			)
			(layer "F.Fab")
		)
		(fp_line
			(start 0.120396 0.2794)
			(end -0.12065 0.2794)
			(stroke
				(width 0.1)
				(type default)
			)
			(layer "F.Fab")
		)
		(fp_line
			(start -0.12065 -0.2794)
			(end 0.12065 -0.2794)
			(stroke
				(width 0.1)
				(type default)
			)
			(layer "F.Fab")
		)
		(fp_line
			(start 0.12065 -0.2794)
			(end 0.12065 -0.3048)
			(stroke
				(width 0.1)
				(type default)
			)
			(layer "F.Fab")
		)
		(fp_line
			(start 0.12065 -0.3048)
			(end 0.67945 -0.3048)
			(stroke
				(width 0.1)
				(type default)
			)
			(layer "F.Fab")
		)
		(fp_line
			(start 0.67945 -0.3048)
			(end 0.67945 0.3048)
			(stroke
				(width 0.1)
				(type default)
			)
			(layer "F.Fab")
		)
		(fp_line
			(start -0.67945 -0.305054)
			(end -0.12065 -0.305054)
			(stroke
				(width 0.1)
				(type default)
			)
			(layer "F.Fab")
		)
		(fp_line
			(start -0.12065 -0.305054)
			(end -0.12065 -0.2794)
			(stroke
				(width 0.1)
				(type default)
			)
			(layer "F.Fab")
		)
		(pad "1" smd circle
			(at -0.40005 0 270)
			(size 0 0)
			(layers "F.Cu" "F.Mask" "F.Paste")
			(net "P3V3_AUX")
		)
		(pad "2" smd circle
			(at 0.40005 0 270)
			(size 0 0)
			(layers "F.Cu" "F.Mask" "F.Paste")
			(net "USB_HUB2_TI_SMBUSZ_MRP_PROG_FUNC2")
		)
	)
	(footprint ""
		(layer "F.Cu")
		(at 178.851814 -410.630624)
		(property "Reference" "R348"
			(at 0 0 0)
			(layer "F.SilkS")
			(hide yes)
			(effects
				(font
					(size 1.27 1.27)
				)
			)
		)
		(property "Value" ""
			(at 0 0 0)
			(layer "F.Fab")
			(effects
				(font
					(size 1.27 1.27)
				)
			)
		)
		(duplicate_pad_numbers_are_jumpers no)
		(fp_line
			(start -0.7874 -0.4064)
			(end 0.7874 -0.4064)
			(stroke
				(width 0.1524)
				(type default)
			)
			(layer "F.SilkS")
		)
		(fp_line
			(start -0.7874 0.4064)
			(end -0.7874 -0.4064)
			(stroke
				(width 0.1524)
				(type default)
			)
			(layer "F.SilkS")
		)
		(fp_line
			(start 0.7874 -0.4064)
			(end 0.7874 0.4064)
			(stroke
				(width 0.1524)
				(type default)
			)
			(layer "F.SilkS")
		)
		(fp_line
			(start 0.7874 0.4064)
			(end -0.7874 0.4064)
			(stroke
				(width 0.1524)
				(type default)
			)
			(layer "F.SilkS")
		)
		(fp_line
			(start -0.67945 -0.305054)
			(end -0.12065 -0.305054)
			(stroke
				(width 0.1)
				(type default)
			)
			(layer "F.Fab")
		)
		(fp_line
			(start -0.67945 0.3048)
			(end -0.67945 -0.305054)
			(stroke
				(width 0.1)
				(type default)
			)
			(layer "F.Fab")
		)
		(fp_line
			(start -0.12065 -0.305054)
			(end -0.12065 -0.2794)
			(stroke
				(width 0.1)
				(type default)
			)
			(layer "F.Fab")
		)
		(fp_line
			(start -0.12065 -0.2794)
			(end 0.12065 -0.2794)
			(stroke
				(width 0.1)
				(type default)
			)
			(layer "F.Fab")
		)
		(fp_line
			(start -0.12065 0.2794)
			(end -0.12065 0.3048)
			(stroke
				(width 0.1)
				(type default)
			)
			(layer "F.Fab")
		)
		(fp_line
			(start -0.12065 0.3048)
			(end -0.67945 0.3048)
			(stroke
				(width 0.1)
				(type default)
			)
			(layer "F.Fab")
		)
		(fp_line
			(start 0.120396 0.2794)
			(end -0.12065 0.2794)
			(stroke
				(width 0.1)
				(type default)
			)
			(layer "F.Fab")
		)
		(fp_line
			(start 0.120396 0.3048)
			(end 0.120396 0.2794)
			(stroke
				(width 0.1)
				(type default)
			)
			(layer "F.Fab")
		)
		(fp_line
			(start 0.12065 -0.3048)
			(end 0.67945 -0.3048)
			(stroke
				(width 0.1)
				(type default)
			)
			(layer "F.Fab")
		)
		(fp_line
			(start 0.12065 -0.2794)
			(end 0.12065 -0.3048)
			(stroke
				(width 0.1)
				(type default)
			)
			(layer "F.Fab")
		)
		(fp_line
			(start 0.67945 -0.3048)
			(end 0.67945 0.3048)
			(stroke
				(width 0.1)
				(type default)
			)
			(layer "F.Fab")
		)
		(fp_line
			(start 0.67945 0.3048)
			(end 0.120396 0.3048)
			(stroke
				(width 0.1)
				(type default)
			)
			(layer "F.Fab")
		)
		(pad "1" smd circle
			(at -0.40005 0)
			(size 0 0)
			(layers "F.Cu" "F.Mask" "F.Paste")
			(net "SMB_SML1_PMBUS_HSC_SDA")
		)
		(pad "2" smd circle
			(at 0.40005 0)
			(size 0 0)
			(layers "F.Cu" "F.Mask" "F.Paste")
			(net "SMB_SML1_PMBUS_HSC_R1_SDA")
		)
	)
	(footprint ""
		(layer "F.Cu")
		(at 108.3564 -397.03248 90)
		(property "Reference" "R690"
			(at 0 0 90)
			(layer "F.SilkS")
			(hide yes)
			(effects
				(font
					(size 1.27 1.27)
				)
			)
		)
		(property "Value" ""
			(at 0 0 90)
			(layer "F.Fab")
			(effects
				(font
					(size 1.27 1.27)
				)
			)
		)
		(duplicate_pad_numbers_are_jumpers no)
		(fp_line
			(start 0.32512 -0.175006)
			(end 0.32512 0.175006)
			(stroke
				(width 0.1)
				(type default)
			)
			(layer "F.Fab")
		)
		(fp_line
			(start -0.32512 -0.175006)
			(end 0.32512 -0.175006)
			(stroke
				(width 0.1)
				(type default)
			)
			(layer "F.Fab")
		)
		(fp_line
			(start 0.32512 0.175006)
			(end -0.32512 0.175006)
			(stroke
				(width 0.1)
				(type default)
			)
			(layer "F.Fab")
		)
		(fp_line
			(start -0.32512 0.175006)
			(end -0.32512 -0.175006)
			(stroke
				(width 0.1)
				(type default)
			)
			(layer "F.Fab")
		)
		(pad "1" smd rect
			(at -0.2667 0 90)
			(size 0.3048 0.381)
			(layers "F.Cu" "F.Mask" "F.Paste")
			(net "SMB_RT_CPU1_P1_ROM_R_SDA")
		)
		(pad "2" smd rect
			(at 0.2667 0 270)
			(size 0.3048 0.381)
			(layers "F.Cu" "F.Mask" "F.Paste")
			(net "SMB_RT_CPU1_P1_ROM_SDA")
		)
	)
)
